# S9S_MB_2U (Grand Teton) — schematic netlist excerpt (pin names and nets, part order shuffled) for the footprints in the layout excerpt that follows; sources: Cadence DE-HDL packaged netlist, KiCad conversion of 03242023_DA0F0TMBIJ0_F0T_Motherboard_J_brd_V01_OCP.brd

C1097  Q_CAP  0.1UF 6.3V 10% X6S  pkg C0201  page 181 : A = USB3_PCH_TX_DN<4> ; B = USB3_PCH_TX_C_DN<4>
C68  Q_CAP  2.2UF 6.3V 20% X6S  pkg C0402  page 104 : A = P3V3_AUX ; B = GND
R2490  Q_RES  1K 1% CHIP  pkg 0402LF  page 115 : A = PWRGD_FAIL_CPU0_AB ; B = PWRGD_FAIL_CPU0_AB_R1

(kicad_pcb
	(version 20260206)
	(generator "pcbnew")
	(generator_version "10.0")
	(general
		(thickness 1.6)
		(legacy_teardrops no)
	)
	(paper "A4")
	(title_block
		(title "03242023_DA0F0TMBIJ0_F0T_Motherboard_J_brd_V01_OCP.brd")
		(comment 1 "Grand Teton / footprints 5506-5508 of 6105")
	)
	(layers
		(0 "F.Cu" signal "TOP")
		(4 "In1.Cu" signal "GND")
		(6 "In2.Cu" signal "IN1")
		(8 "In3.Cu" signal "GND1")
		(10 "In4.Cu" signal "IN2")
		(12 "In5.Cu" signal "GND2")
		(14 "In6.Cu" signal "IN3")
		(16 "In7.Cu" signal "GND3")
		(18 "In8.Cu" signal "VCC")
		(20 "In9.Cu" signal "VCC1")
		(22 "In10.Cu" signal "GND4")
		(24 "In11.Cu" signal "IN4")
		(26 "In12.Cu" signal "GND5")
		(28 "In13.Cu" signal "IN5")
		(30 "In14.Cu" signal "GND6")
		(32 "In15.Cu" signal "IN6")
		(34 "In16.Cu" signal "GND7")
		(2 "B.Cu" signal "BOTTOM")
		(9 "F.Adhes" user "F.Adhesive")
		(11 "B.Adhes" user "B.Adhesive")
		(13 "F.Paste" user "Package Geometry/Pastemask Top")
		(15 "B.Paste" user "Package Geometry/Pastemask Bottom")
		(5 "F.SilkS" user "Ref Des/Silkscreen Top")
		(7 "B.SilkS" user "Ref Des/Silkscreen Bottom")
		(1 "F.Mask" user "Board Geometry/Soldermask Top")
		(3 "B.Mask" user "Board Geometry/Soldermask Bottom")
		(17 "Dwgs.User" user "User.Drawings")
		(19 "Cmts.User" user "User.Comments")
		(21 "Eco1.User" user "User.Eco1")
		(23 "Eco2.User" user "User.Eco2")
		(25 "Edge.Cuts" user "Board Geometry/Outline")
		(27 "Margin" user)
		(31 "F.CrtYd" user "Package Geometry/Place Bound Top")
		(29 "B.CrtYd" user "Package Geometry/Place Bound Bottom")
		(35 "F.Fab" user "Ref Des/Assembly Top")
		(33 "B.Fab" user "Ref Des/Assembly Bottom")
	)
	(footprint ""
		(layer "B.Cu")
		(at 8.153146 -319.268856 180)
		(property "Reference" "C68"
			(at 0 0 0)
			(layer "B.SilkS")
			(hide yes)
			(effects
				(font
					(size 1.27 1.27)
				)
				(justify mirror)
			)
		)
		(property "Value" ""
			(at 0 0 0)
			(layer "B.Fab")
			(effects
				(font
					(size 1.27 1.27)
				)
				(justify mirror)
			)
		)
		(duplicate_pad_numbers_are_jumpers no)
		(fp_line
			(start 0.7874 0.4064)
			(end 0.7874 -0.4064)
			(stroke
				(width 0.1524)
				(type default)
			)
			(layer "B.SilkS")
		)
		(fp_line
			(start 0.7874 -0.4064)
			(end -0.7874 -0.4064)
			(stroke
				(width 0.1524)
				(type default)
			)
			(layer "B.SilkS")
		)
		(fp_line
			(start -0.7874 0.4064)
			(end 0.7874 0.4064)
			(stroke
				(width 0.1524)
				(type default)
			)
			(layer "B.SilkS")
		)
		(fp_line
			(start -0.7874 -0.4064)
			(end -0.7874 0.4064)
			(stroke
				(width 0.1524)
				(type default)
			)
			(layer "B.SilkS")
		)
		(fp_line
			(start 0.67945 0.3048)
			(end 0.67945 -0.305054)
			(stroke
				(width 0.1)
				(type default)
			)
			(layer "B.Fab")
		)
		(fp_line
			(start 0.67945 -0.305054)
			(end 0.12065 -0.305054)
			(stroke
				(width 0.1)
				(type default)
			)
			(layer "B.Fab")
		)
		(fp_line
			(start 0.12065 0.3048)
			(end 0.67945 0.3048)
			(stroke
				(width 0.1)
				(type default)
			)
			(layer "B.Fab")
		)
		(fp_line
			(start 0.12065 0.2794)
			(end 0.12065 0.3048)
			(stroke
				(width 0.1)
				(type default)
			)
			(layer "B.Fab")
		)
		(fp_line
			(start 0.12065 -0.2794)
			(end -0.12065 -0.2794)
			(stroke
				(width 0.1)
				(type default)
			)
			(layer "B.Fab")
		)
		(fp_line
			(start 0.12065 -0.305054)
			(end 0.12065 -0.2794)
			(stroke
				(width 0.1)
				(type default)
			)
			(layer "B.Fab")
		)
		(fp_line
			(start -0.120396 0.3048)
			(end -0.120396 0.2794)
			(stroke
				(width 0.1)
				(type default)
			)
			(layer "B.Fab")
		)
		(fp_line
			(start -0.120396 0.2794)
			(end 0.12065 0.2794)
			(stroke
				(width 0.1)
				(type default)
			)
			(layer "B.Fab")
		)
		(fp_line
			(start -0.12065 -0.2794)
			(end -0.12065 -0.3048)
			(stroke
				(width 0.1)
				(type default)
			)
			(layer "B.Fab")
		)
		(fp_line
			(start -0.12065 -0.3048)
			(end -0.67945 -0.3048)
			(stroke
				(width 0.1)
				(type default)
			)
			(layer "B.Fab")
		)
		(fp_line
			(start -0.67945 0.3048)
			(end -0.120396 0.3048)
			(stroke
				(width 0.1)
				(type default)
			)
			(layer "B.Fab")
		)
		(fp_line
			(start -0.67945 -0.3048)
			(end -0.67945 0.3048)
			(stroke
				(width 0.1)
				(type default)
			)
			(layer "B.Fab")
		)
		(pad "1" smd circle
			(at 0.40005 0)
			(size 0 0)
			(layers "B.Cu" "B.Mask" "B.Paste")
			(net "P3V3_AUX")
		)
		(pad "2" smd circle
			(at -0.40005 0)
			(size 0 0)
			(layers "B.Cu" "B.Mask" "B.Paste")
			(net "GND")
		)
	)
	(footprint ""
		(layer "B.Cu")
		(at 312.592974 -317.06566 90)
		(property "Reference" "R2490"
			(at 0 0 90)
			(layer "B.SilkS")
			(hide yes)
			(effects
				(font
					(size 1.27 1.27)
				)
				(justify mirror)
			)
		)
		(property "Value" ""
			(at 0 0 90)
			(layer "B.Fab")
			(effects
				(font
					(size 1.27 1.27)
				)
				(justify mirror)
			)
		)
		(duplicate_pad_numbers_are_jumpers no)
		(fp_line
			(start 0.7874 -0.4064)
			(end -0.7874 -0.4064)
			(stroke
				(width 0.1524)
				(type default)
			)
			(layer "B.SilkS")
		)
		(fp_line
			(start -0.7874 -0.4064)
			(end -0.7874 0.4064)
			(stroke
				(width 0.1524)
				(type default)
			)
			(layer "B.SilkS")
		)
		(fp_line
			(start 0.7874 0.4064)
			(end 0.7874 -0.4064)
			(stroke
				(width 0.1524)
				(type default)
			)
			(layer "B.SilkS")
		)
		(fp_line
			(start -0.7874 0.4064)
			(end 0.7874 0.4064)
			(stroke
				(width 0.1524)
				(type default)
			)
			(layer "B.SilkS")
		)
		(fp_line
			(start 0.67945 -0.305054)
			(end 0.12065 -0.305054)
			(stroke
				(width 0.1)
				(type default)
			)
			(layer "B.Fab")
		)
		(fp_line
			(start 0.12065 -0.305054)
			(end 0.12065 -0.2794)
			(stroke
				(width 0.1)
				(type default)
			)
			(layer "B.Fab")
		)
		(fp_line
			(start -0.12065 -0.3048)
			(end -0.67945 -0.3048)
			(stroke
				(width 0.1)
				(type default)
			)
			(layer "B.Fab")
		)
		(fp_line
			(start -0.67945 -0.3048)
			(end -0.67945 0.3048)
			(stroke
				(width 0.1)
				(type default)
			)
			(layer "B.Fab")
		)
		(fp_line
			(start 0.12065 -0.2794)
			(end -0.12065 -0.2794)
			(stroke
				(width 0.1)
				(type default)
			)
			(layer "B.Fab")
		)
		(fp_line
			(start -0.12065 -0.2794)
			(end -0.12065 -0.3048)
			(stroke
				(width 0.1)
				(type default)
			)
			(layer "B.Fab")
		)
		(fp_line
			(start 0.12065 0.2794)
			(end 0.12065 0.3048)
			(stroke
				(width 0.1)
				(type default)
			)
			(layer "B.Fab")
		)
		(fp_line
			(start -0.120396 0.2794)
			(end 0.12065 0.2794)
			(stroke
				(width 0.1)
				(type default)
			)
			(layer "B.Fab")
		)
		(fp_line
			(start 0.67945 0.3048)
			(end 0.67945 -0.305054)
			(stroke
				(width 0.1)
				(type default)
			)
			(layer "B.Fab")
		)
		(fp_line
			(start 0.12065 0.3048)
			(end 0.67945 0.3048)
			(stroke
				(width 0.1)
				(type default)
			)
			(layer "B.Fab")
		)
		(fp_line
			(start -0.120396 0.3048)
			(end -0.120396 0.2794)
			(stroke
				(width 0.1)
				(type default)
			)
			(layer "B.Fab")
		)
		(fp_line
			(start -0.67945 0.3048)
			(end -0.120396 0.3048)
			(stroke
				(width 0.1)
				(type default)
			)
			(layer "B.Fab")
		)
		(pad "1" smd circle
			(at 0.40005 0 270)
			(size 0 0)
			(layers "B.Cu" "B.Mask" "B.Paste")
			(net "PWRGD_FAIL_CPU0_AB")
		)
		(pad "2" smd circle
			(at -0.40005 0 270)
			(size 0 0)
			(layers "B.Cu" "B.Mask" "B.Paste")
			(net "PWRGD_FAIL_CPU0_AB_R1")
		)
	)
	(footprint ""
		(layer "B.Cu")
		(at 125.052836 -25.774142 180)
		(property "Reference" "C1097"
			(at 0 0 0)
			(layer "B.SilkS")
			(hide yes)
			(effects
				(font
					(size 1.27 1.27)
				)
				(justify mirror)
			)
		)
		(property "Value" ""
			(at 0 0 0)
			(layer "B.Fab")
			(effects
				(font
					(size 1.27 1.27)
				)
				(justify mirror)
			)
		)
		(duplicate_pad_numbers_are_jumpers no)
		(fp_line
			(start 0.299974 0.150114)
			(end 0.299974 -0.150114)
			(stroke
				(width 0.1)
				(type default)
			)
			(layer "B.Fab")
		)
		(fp_line
			(start 0.299974 -0.150114)
			(end -0.299974 -0.150114)
			(stroke
				(width 0.1)
				(type default)
			)
			(layer "B.Fab")
		)
		(fp_line
			(start -0.299974 0.150114)
			(end 0.299974 0.150114)
			(stroke
				(width 0.1)
				(type default)
			)
			(layer "B.Fab")
		)
		(fp_line
			(start -0.299974 -0.150114)
			(end -0.299974 0.150114)
			(stroke
				(width 0.1)
				(type default)
			)
			(layer "B.Fab")
		)
		(pad "1" smd rect
			(at 0.2667 0)
			(size 0.3048 0.381)
			(layers "B.Cu" "B.Mask" "B.Paste")
			(net "USB3_PCH_TX_DN<4>")
		)
		(pad "2" smd rect
			(at -0.2667 0)
			(size 0.3048 0.381)
			(layers "B.Cu" "B.Mask" "B.Paste")
			(net "USB3_PCH_TX_C_DN<4>")
		)
	)
)
